(kicad_pcb
	(version 20260206)
	(generator "pcbnew")
	(generator_version "10.0")
	(general
		(thickness 1.6)
		(legacy_teardrops no)
	)
	(paper "A4")
	(title_block
		(title "04192023_DAF0TMB3IC0_F0TG_MB_C_brd_V02_OCP.brd")
		(comment 1 "Grand Teton / footprints 4416-4422 of 8354")
	)
	(layers
		(0 "F.Cu" signal "TOP")
		(4 "In1.Cu" signal "GND")
		(6 "In2.Cu" signal "IN1")
		(8 "In3.Cu" signal "GND1")
		(10 "In4.Cu" signal "IN2")
		(12 "In5.Cu" signal "GND2")
		(14 "In6.Cu" signal "IN3")
		(16 "In7.Cu" signal "GND3")
		(18 "In8.Cu" signal "VCC")
		(20 "In9.Cu" signal "VCC1")
		(22 "In10.Cu" signal "GND4")
		(24 "In11.Cu" signal "IN4")
		(26 "In12.Cu" signal "GND5")
		(28 "In13.Cu" signal "IN5")
		(30 "In14.Cu" signal "GND6")
		(32 "In15.Cu" signal "IN6")
		(34 "In16.Cu" signal "GND7")
		(2 "B.Cu" signal "BOTTOM")
		(9 "F.Adhes" user "F.Adhesive")
		(11 "B.Adhes" user "B.Adhesive")
		(13 "F.Paste" user "Package Geometry/Pastemask Top")
		(15 "B.Paste" user "Package Geometry/Pastemask Bottom")
		(5 "F.SilkS" user "Ref Des/Silkscreen Top")
		(7 "B.SilkS" user "Ref Des/Silkscreen Bottom")
		(1 "F.Mask" user "Board Geometry/Soldermask Top")
		(3 "B.Mask" user "Board Geometry/Soldermask Bottom")
		(17 "Dwgs.User" user "User.Drawings")
		(19 "Cmts.User" user "User.Comments")
		(21 "Eco1.User" user "User.Eco1")
		(23 "Eco2.User" user "User.Eco2")
		(25 "Edge.Cuts" user "Board Geometry/Outline")
		(27 "Margin" user)
		(31 "F.CrtYd" user "Package Geometry/Place Bound Top")
		(29 "B.CrtYd" user "Package Geometry/Place Bound Bottom")
		(35 "F.Fab" user "Ref Des/Assembly Top")
		(33 "B.Fab" user "Ref Des/Assembly Bottom")
	)
	(footprint ""
		(layer "F.Cu")
		(at 421.262302 -435.186836 -90)
		(property "Reference" "R4569"
			(at 0 0 270)
			(layer "F.SilkS")
			(hide yes)
			(effects
				(font
					(size 1.27 1.27)
				)
			)
		)
		(property "Value" ""
			(at 0 0 270)
			(layer "F.Fab")
			(effects
				(font
					(size 1.27 1.27)
				)
			)
		)
		(duplicate_pad_numbers_are_jumpers no)
		(fp_line
			(start -0.7874 0.4064)
			(end -0.7874 -0.4064)
			(stroke
				(width 0.1524)
				(type default)
			)
			(layer "F.SilkS")
		)
		(fp_line
			(start 0.7874 0.4064)
			(end -0.7874 0.4064)
			(stroke
				(width 0.1524)
				(type default)
			)
			(layer "F.SilkS")
		)
		(fp_line
			(start -0.7874 -0.4064)
			(end 0.7874 -0.4064)
			(stroke
				(width 0.1524)
				(type default)
			)
			(layer "F.SilkS")
		)
		(fp_line
			(start 0.7874 -0.4064)
			(end 0.7874 0.4064)
			(stroke
				(width 0.1524)
				(type default)
			)
			(layer "F.SilkS")
		)
		(fp_line
			(start -0.67945 0.3048)
			(end -0.67945 -0.305054)
			(stroke
				(width 0.1)
				(type default)
			)
			(layer "F.Fab")
		)
		(fp_line
			(start -0.12065 0.3048)
			(end -0.67945 0.3048)
			(stroke
				(width 0.1)
				(type default)
			)
			(layer "F.Fab")
		)
		(fp_line
			(start 0.120396 0.3048)
			(end 0.120396 0.2794)
			(stroke
				(width 0.1)
				(type default)
			)
			(layer "F.Fab")
		)
		(fp_line
			(start 0.67945 0.3048)
			(end 0.120396 0.3048)
			(stroke
				(width 0.1)
				(type default)
			)
			(layer "F.Fab")
		)
		(fp_line
			(start -0.12065 0.2794)
			(end -0.12065 0.3048)
			(stroke
				(width 0.1)
				(type default)
			)
			(layer "F.Fab")
		)
		(fp_line
			(start 0.120396 0.2794)
			(end -0.12065 0.2794)
			(stroke
				(width 0.1)
				(type default)
			)
			(layer "F.Fab")
		)
		(fp_line
			(start -0.12065 -0.2794)
			(end 0.12065 -0.2794)
			(stroke
				(width 0.1)
				(type default)
			)
			(layer "F.Fab")
		)
		(fp_line
			(start 0.12065 -0.2794)
			(end 0.12065 -0.3048)
			(stroke
				(width 0.1)
				(type default)
			)
			(layer "F.Fab")
		)
		(fp_line
			(start 0.12065 -0.3048)
			(end 0.67945 -0.3048)
			(stroke
				(width 0.1)
				(type default)
			)
			(layer "F.Fab")
		)
		(fp_line
			(start 0.67945 -0.3048)
			(end 0.67945 0.3048)
			(stroke
				(width 0.1)
				(type default)
			)
			(layer "F.Fab")
		)
		(fp_line
			(start -0.67945 -0.305054)
			(end -0.12065 -0.305054)
			(stroke
				(width 0.1)
				(type default)
			)
			(layer "F.Fab")
		)
		(fp_line
			(start -0.12065 -0.305054)
			(end -0.12065 -0.2794)
			(stroke
				(width 0.1)
				(type default)
			)
			(layer "F.Fab")
		)
		(pad "1" smd circle
			(at -0.40005 0 270)
			(size 0 0)
			(layers "F.Cu" "F.Mask" "F.Paste")
			(net "GPU_3V3IO_RSVD1")
		)
		(pad "2" smd circle
			(at 0.40005 0 270)
			(size 0 0)
			(layers "F.Cu" "F.Mask" "F.Paste")
			(net "GPU_3V3IO_RSVD1_ISO")
		)
	)
	(footprint ""
		(layer "F.Cu")
		(at 87.590884 -408.517344 -90)
		(property "Reference" "C6656"
			(at 0 0 270)
			(layer "F.SilkS")
			(hide yes)
			(effects
				(font
					(size 1.27 1.27)
				)
			)
		)
		(property "Value" ""
			(at 0 0 270)
			(layer "F.Fab")
			(effects
				(font
					(size 1.27 1.27)
				)
			)
		)
		(duplicate_pad_numbers_are_jumpers no)
		(fp_line
			(start -0.299974 0.150114)
			(end -0.299974 -0.150114)
			(stroke
				(width 0.1)
				(type default)
			)
			(layer "F.Fab")
		)
		(fp_line
			(start 0.299974 0.150114)
			(end -0.299974 0.150114)
			(stroke
				(width 0.1)
				(type default)
			)
			(layer "F.Fab")
		)
		(fp_line
			(start -0.299974 -0.150114)
			(end 0.299974 -0.150114)
			(stroke
				(width 0.1)
				(type default)
			)
			(layer "F.Fab")
		)
		(fp_line
			(start 0.299974 -0.150114)
			(end 0.299974 0.150114)
			(stroke
				(width 0.1)
				(type default)
			)
			(layer "F.Fab")
		)
		(pad "1" smd rect
			(at -0.2667 0 270)
			(size 0.3048 0.381)
			(layers "F.Cu" "F.Mask" "F.Paste")
			(net "P5E_CPU1_P0_TX_BUF_C_DN<13>")
		)
		(pad "2" smd rect
			(at 0.2667 0 270)
			(size 0.3048 0.381)
			(layers "F.Cu" "F.Mask" "F.Paste")
			(net "P5E_CPU1_P0_TX_BUF_DN<13>")
		)
	)
	(footprint ""
		(layer "F.Cu")
		(at 214.973408 -67.220084 -90)
		(property "Reference" "PD113"
			(at 3.924808 2.193544 90)
			(unlocked yes)
			(layer "F.SilkS")
			(effects
				(font
					(size 0.7874 0.5842)
					(thickness 0.1524)
				)
				(justify left)
			)
		)
		(property "Value" ""
			(at 0 0 270)
			(layer "F.Fab")
			(effects
				(font
					(size 1.27 1.27)
				)
			)
		)
		(duplicate_pad_numbers_are_jumpers no)
		(fp_line
			(start -3.400044 1.459992)
			(end -3.400044 -1.459992)
			(stroke
				(width 0.1524)
				(type default)
			)
			(layer "F.SilkS")
		)
		(fp_line
			(start 4.107942 1.459992)
			(end -3.400044 1.459992)
			(stroke
				(width 0.1524)
				(type default)
			)
			(layer "F.SilkS")
		)
		(fp_line
			(start -3.400044 -1.459992)
			(end 4.107942 -1.459992)
			(stroke
				(width 0.1524)
				(type default)
			)
			(layer "F.SilkS")
		)
		(fp_line
			(start 4.107942 -1.459992)
			(end 4.107942 1.459992)
			(stroke
				(width 0.1524)
				(type default)
			)
			(layer "F.SilkS")
		)
		(fp_rect
			(start 4.107942 1.459992)
			(end 3.308096 -1.459992)
			(stroke
				(width 0)
				(type default)
			)
			(fill yes)
			(layer "F.SilkS")
		)
		(fp_line
			(start -2.29997 1.459992)
			(end -2.29997 -1.459992)
			(stroke
				(width 0.1)
				(type default)
			)
			(layer "F.Fab")
		)
		(fp_line
			(start 2.29997 1.459992)
			(end -2.29997 1.459992)
			(stroke
				(width 0.1)
				(type default)
			)
			(layer "F.Fab")
		)
		(fp_line
			(start -2.29997 -1.459992)
			(end 2.29997 -1.459992)
			(stroke
				(width 0.1)
				(type default)
			)
			(layer "F.Fab")
		)
		(fp_line
			(start 2.29997 -1.459992)
			(end 2.29997 1.459992)
			(stroke
				(width 0.1)
				(type default)
			)
			(layer "F.Fab")
		)
		(fp_text user "+"
			(at -4.7752 -0.12065 270)
			(unlocked yes)
			(layer "F.SilkS")
			(effects
				(font
					(size 1.905 1.4224)
					(thickness 0.1524)
				)
				(justify left)
			)
		)
		(fp_text user "-"
			(at 4.545838 -1.956054 90)
			(unlocked yes)
			(layer "F.SilkS")
			(effects
				(font
					(size 1.905 1.4224)
					(thickness 0.1524)
				)
				(justify left)
			)
		)
		(fp_text user "-"
			(at 5.4102 0.29845 90)
			(unlocked yes)
			(layer "F.Fab")
			(effects
				(font
					(size 1.905 1.4224)
					(thickness 0.1524)
				)
				(justify left)
			)
		)
		(fp_text user "+"
			(at -4.7752 -0.12065 270)
			(unlocked yes)
			(layer "F.Fab")
			(effects
				(font
					(size 1.905 1.4224)
					(thickness 0.1524)
				)
				(justify left)
			)
		)
		(pad "A" smd rect
			(at -1.999996 0)
			(size 1.7018 2.5146)
			(layers "F.Cu" "F.Mask" "F.Paste")
			(net "GND")
		)
		(pad "C" smd rect
			(at 1.999996 0)
			(size 1.7018 2.5146)
			(layers "F.Cu" "F.Mask" "F.Paste")
			(net "P3V3_E1S_0_R")
		)
	)
	(footprint ""
		(layer "F.Cu")
		(at 205.590394 -346.505022)
		(property "Reference" "PC6000"
			(at 0 0 0)
			(layer "F.SilkS")
			(hide yes)
			(effects
				(font
					(size 1.27 1.27)
				)
			)
		)
		(property "Value" ""
			(at 0 0 0)
			(layer "F.Fab")
			(effects
				(font
					(size 1.27 1.27)
				)
			)
		)
		(duplicate_pad_numbers_are_jumpers no)
		(fp_line
			(start -0.7874 -0.4064)
			(end 0.7874 -0.4064)
			(stroke
				(width 0.1524)
				(type default)
			)
			(layer "F.SilkS")
		)
		(fp_line
			(start -0.7874 0.4064)
			(end -0.7874 -0.4064)
			(stroke
				(width 0.1524)
				(type default)
			)
			(layer "F.SilkS")
		)
		(fp_line
			(start 0.7874 -0.4064)
			(end 0.7874 0.4064)
			(stroke
				(width 0.1524)
				(type default)
			)
			(layer "F.SilkS")
		)
		(fp_line
			(start 0.7874 0.4064)
			(end -0.7874 0.4064)
			(stroke
				(width 0.1524)
				(type default)
			)
			(layer "F.SilkS")
		)
		(fp_line
			(start -0.67945 -0.305054)
			(end -0.12065 -0.305054)
			(stroke
				(width 0.1)
				(type default)
			)
			(layer "F.Fab")
		)
		(fp_line
			(start -0.67945 0.3048)
			(end -0.67945 -0.305054)
			(stroke
				(width 0.1)
				(type default)
			)
			(layer "F.Fab")
		)
		(fp_line
			(start -0.12065 -0.305054)
			(end -0.12065 -0.2794)
			(stroke
				(width 0.1)
				(type default)
			)
			(layer "F.Fab")
		)
		(fp_line
			(start -0.12065 -0.2794)
			(end 0.12065 -0.2794)
			(stroke
				(width 0.1)
				(type default)
			)
			(layer "F.Fab")
		)
		(fp_line
			(start -0.12065 0.2794)
			(end -0.12065 0.3048)
			(stroke
				(width 0.1)
				(type default)
			)
			(layer "F.Fab")
		)
		(fp_line
			(start -0.12065 0.3048)
			(end -0.67945 0.3048)
			(stroke
				(width 0.1)
				(type default)
			)
			(layer "F.Fab")
		)
		(fp_line
			(start 0.120396 0.2794)
			(end -0.12065 0.2794)
			(stroke
				(width 0.1)
				(type default)
			)
			(layer "F.Fab")
		)
		(fp_line
			(start 0.120396 0.3048)
			(end 0.120396 0.2794)
			(stroke
				(width 0.1)
				(type default)
			)
			(layer "F.Fab")
		)
		(fp_line
			(start 0.12065 -0.3048)
			(end 0.67945 -0.3048)
			(stroke
				(width 0.1)
				(type default)
			)
			(layer "F.Fab")
		)
		(fp_line
			(start 0.12065 -0.2794)
			(end 0.12065 -0.3048)
			(stroke
				(width 0.1)
				(type default)
			)
			(layer "F.Fab")
		)
		(fp_line
			(start 0.67945 -0.3048)
			(end 0.67945 0.3048)
			(stroke
				(width 0.1)
				(type default)
			)
			(layer "F.Fab")
		)
		(fp_line
			(start 0.67945 0.3048)
			(end 0.120396 0.3048)
			(stroke
				(width 0.1)
				(type default)
			)
			(layer "F.Fab")
		)
		(pad "1" smd circle
			(at -0.40005 0)
			(size 0 0)
			(layers "F.Cu" "F.Mask" "F.Paste")
			(net "P12V_AUX")
		)
		(pad "2" smd circle
			(at 0.40005 0)
			(size 0 0)
			(layers "F.Cu" "F.Mask" "F.Paste")
			(net "GND")
		)
	)
	(footprint ""
		(layer "F.Cu")
		(at 305.013106 -346.714572 -90)
		(property "Reference" "PC111_C1P0_4"
			(at 0 0 270)
			(layer "F.SilkS")
			(hide yes)
			(effects
				(font
					(size 1.27 1.27)
				)
			)
		)
		(property "Value" ""
			(at 0 0 270)
			(layer "F.Fab")
			(effects
				(font
					(size 1.27 1.27)
				)
			)
		)
		(duplicate_pad_numbers_are_jumpers no)
		(fp_line
			(start -0.7874 0.4064)
			(end -0.7874 -0.4064)
			(stroke
				(width 0.1524)
				(type default)
			)
			(layer "F.SilkS")
		)
		(fp_line
			(start 0.7874 0.4064)
			(end -0.7874 0.4064)
			(stroke
				(width 0.1524)
				(type default)
			)
			(layer "F.SilkS")
		)
		(fp_line
			(start -0.7874 -0.4064)
			(end 0.7874 -0.4064)
			(stroke
				(width 0.1524)
				(type default)
			)
			(layer "F.SilkS")
		)
		(fp_line
			(start 0.7874 -0.4064)
			(end 0.7874 0.4064)
			(stroke
				(width 0.1524)
				(type default)
			)
			(layer "F.SilkS")
		)
		(fp_line
			(start -0.67945 0.3048)
			(end -0.67945 -0.305054)
			(stroke
				(width 0.1)
				(type default)
			)
			(layer "F.Fab")
		)
		(fp_line
			(start -0.12065 0.3048)
			(end -0.67945 0.3048)
			(stroke
				(width 0.1)
				(type default)
			)
			(layer "F.Fab")
		)
		(fp_line
			(start 0.120396 0.3048)
			(end 0.120396 0.2794)
			(stroke
				(width 0.1)
				(type default)
			)
			(layer "F.Fab")
		)
		(fp_line
			(start 0.67945 0.3048)
			(end 0.120396 0.3048)
			(stroke
				(width 0.1)
				(type default)
			)
			(layer "F.Fab")
		)
		(fp_line
			(start -0.12065 0.2794)
			(end -0.12065 0.3048)
			(stroke
				(width 0.1)
				(type default)
			)
			(layer "F.Fab")
		)
		(fp_line
			(start 0.120396 0.2794)
			(end -0.12065 0.2794)
			(stroke
				(width 0.1)
				(type default)
			)
			(layer "F.Fab")
		)
		(fp_line
			(start -0.12065 -0.2794)
			(end 0.12065 -0.2794)
			(stroke
				(width 0.1)
				(type default)
			)
			(layer "F.Fab")
		)
		(fp_line
			(start 0.12065 -0.2794)
			(end 0.12065 -0.3048)
			(stroke
				(width 0.1)
				(type default)
			)
			(layer "F.Fab")
		)
		(fp_line
			(start 0.12065 -0.3048)
			(end 0.67945 -0.3048)
			(stroke
				(width 0.1)
				(type default)
			)
			(layer "F.Fab")
		)
		(fp_line
			(start 0.67945 -0.3048)
			(end 0.67945 0.3048)
			(stroke
				(width 0.1)
				(type default)
			)
			(layer "F.Fab")
		)
		(fp_line
			(start -0.67945 -0.305054)
			(end -0.12065 -0.305054)
			(stroke
				(width 0.1)
				(type default)
			)
			(layer "F.Fab")
		)
		(fp_line
			(start -0.12065 -0.305054)
			(end -0.12065 -0.2794)
			(stroke
				(width 0.1)
				(type default)
			)
			(layer "F.Fab")
		)
		(pad "1" smd circle
			(at -0.40005 0 270)
			(size 0 0)
			(layers "F.Cu" "F.Mask" "F.Paste")
			(net "PVDDCR_CPU1_P0_PVCC")
		)
		(pad "2" smd circle
			(at 0.40005 0 270)
			(size 0 0)
			(layers "F.Cu" "F.Mask" "F.Paste")
			(net "GND")
		)
	)
	(footprint ""
		(layer "F.Cu")
		(at 109.627924 -387.764274)
		(property "Reference" "R621"
			(at 0 0 0)
			(layer "F.SilkS")
			(hide yes)
			(effects
				(font
					(size 1.27 1.27)
				)
			)
		)
		(property "Value" ""
			(at 0 0 0)
			(layer "F.Fab")
			(effects
				(font
					(size 1.27 1.27)
				)
			)
		)
		(duplicate_pad_numbers_are_jumpers no)
		(fp_line
			(start -0.32512 -0.175006)
			(end 0.32512 -0.175006)
			(stroke
				(width 0.1)
				(type default)
			)
			(layer "F.Fab")
		)
		(fp_line
			(start -0.32512 0.175006)
			(end -0.32512 -0.175006)
			(stroke
				(width 0.1)
				(type default)
			)
			(layer "F.Fab")
		)
		(fp_line
			(start 0.32512 -0.175006)
			(end 0.32512 0.175006)
			(stroke
				(width 0.1)
				(type default)
			)
			(layer "F.Fab")
		)
		(fp_line
			(start 0.32512 0.175006)
			(end -0.32512 0.175006)
			(stroke
				(width 0.1)
				(type default)
			)
			(layer "F.Fab")
		)
		(pad "1" smd rect
			(at -0.2667 0)
			(size 0.3048 0.381)
			(layers "F.Cu" "F.Mask" "F.Paste")
			(net "CLK_100M_RETIMER_CPU1_P3_R_DP")
		)
		(pad "2" smd rect
			(at 0.2667 0 180)
			(size 0.3048 0.381)
			(layers "F.Cu" "F.Mask" "F.Paste")
			(net "CLK_100M_RETIMER_CPU1_P3_DP")
		)
	)
	(footprint ""
		(layer "F.Cu")
		(at 95.885 -78.105)
		(property "Reference" "U33"
			(at -2.032 -2.377948 0)
			(unlocked yes)
			(layer "F.SilkS")
			(effects
				(font
					(size 0.7874 0.5842)
					(thickness 0.1524)
				)
				(justify left)
			)
		)
		(property "Value" ""
			(at 0 0 0)
			(layer "F.Fab")
			(effects
				(font
					(size 1.27 1.27)
				)
			)
		)
		(duplicate_pad_numbers_are_jumpers no)
		(fp_line
			(start -2.0574 -1.651)
			(end -0.381 -1.651)
			(stroke
				(width 0.1524)
				(type default)
			)
			(layer "F.SilkS")
		)
		(fp_line
			(start -2.0574 1.651)
			(end -2.0574 -1.651)
			(stroke
				(width 0.1524)
				(type default)
			)
			(layer "F.SilkS")
		)
		(fp_line
			(start -0.381 -1.651)
			(end 0 -1.016)
			(stroke
				(width 0.1524)
				(type default)
			)
			(layer "F.SilkS")
		)
		(fp_line
			(start 0 -1.016)
			(end 0.381 -1.651)
			(stroke
				(width 0.1524)
				(type default)
			)
			(layer "F.SilkS")
		)
		(fp_line
			(start 0.381 -1.651)
			(end 2.0574 -1.651)
			(stroke
				(width 0.1524)
				(type default)
			)
			(layer "F.SilkS")
		)
		(fp_line
			(start 2.0574 -1.651)
			(end 2.0574 1.651)
			(stroke
				(width 0.1524)
				(type default)
			)
			(layer "F.SilkS")
		)
		(fp_line
			(start 2.0574 1.651)
			(end -2.0574 1.651)
			(stroke
				(width 0.1524)
				(type default)
			)
			(layer "F.SilkS")
		)
		(fp_poly
			(pts
				(xy -2.71272 -0.719328) (xy -2.71272 -1.344168) (xy -2.159 -1.016)
			)
			(stroke
				(width 0)
				(type default)
			)
			(fill yes)
			(layer "F.SilkS")
		)
		(fp_line
			(start -1.599946 -1.199896)
			(end -0.899922 -1.199896)
			(stroke
				(width 0.1)
				(type default)
			)
			(layer "F.Fab")
		)
		(fp_line
			(start -1.599946 1.199896)
			(end -1.599946 -1.199896)
			(stroke
				(width 0.1)
				(type default)
			)
			(layer "F.Fab")
		)
		(fp_line
			(start -0.899922 -1.549908)
			(end 0.899922 -1.549908)
			(stroke
				(width 0.1)
				(type default)
			)
			(layer "F.Fab")
		)
		(fp_line
			(start -0.899922 -1.199896)
			(end -0.899922 -1.549908)
			(stroke
				(width 0.1)
				(type default)
			)
			(layer "F.Fab")
		)
		(fp_line
			(start -0.899922 1.199896)
			(end -1.599946 1.199896)
			(stroke
				(width 0.1)
				(type default)
			)
			(layer "F.Fab")
		)
		(fp_line
			(start -0.899922 1.549908)
			(end -0.899922 1.199896)
			(stroke
				(width 0.1)
				(type default)
			)
			(layer "F.Fab")
		)
		(fp_line
			(start 0.899922 -1.549908)
			(end 0.899922 -1.199896)
			(stroke
				(width 0.1)
				(type default)
			)
			(layer "F.Fab")
		)
		(fp_line
			(start 0.899922 -1.199896)
			(end 1.599946 -1.199896)
			(stroke
				(width 0.1)
				(type default)
			)
			(layer "F.Fab")
		)
		(fp_line
			(start 0.899922 1.199896)
			(end 0.899922 1.549908)
			(stroke
				(width 0.1)
				(type default)
			)
			(layer "F.Fab")
		)
		(fp_line
			(start 0.899922 1.549908)
			(end -0.899922 1.549908)
			(stroke
				(width 0.1)
				(type default)
			)
			(layer "F.Fab")
		)
		(fp_line
			(start 1.599946 -1.199896)
			(end 1.599946 1.199896)
			(stroke
				(width 0.1)
				(type default)
			)
			(layer "F.Fab")
		)
		(fp_line
			(start 1.599946 1.199896)
			(end 0.899922 1.199896)
			(stroke
				(width 0.1)
				(type default)
			)
			(layer "F.Fab")
		)
		(fp_poly
			(pts
				(xy -2.71272 -0.719328) (xy -2.71272 -1.344168) (xy -2.159 -1.016)
			)
			(stroke
				(width 0)
				(type default)
			)
			(fill yes)
			(layer "F.Fab")
		)
		(pad "1" smd rect
			(at -1.225042 -0.94996 270)
			(size 0.5588 1.3462)
			(layers "F.Cu" "F.Mask" "F.Paste")
			(net "Net_10853")
		)
		(pad "2" smd rect
			(at -1.225042 0 270)
			(size 0.5588 1.3462)
			(layers "F.Cu" "F.Mask" "F.Paste")
			(net "HP_LVC3_OCP_V3_2_P12V_R_PWRGD")
		)
		(pad "3" smd rect
			(at -1.225042 0.94996 270)
			(size 0.5588 1.3462)
			(layers "F.Cu" "F.Mask" "F.Paste")
			(net "GND")
		)
		(pad "4" smd rect
			(at 1.225042 0.94996 270)
			(size 0.5588 1.3462)
			(layers "F.Cu" "F.Mask" "F.Paste")
			(net "P12V_OCP_V3_2_PLD_R_PWRGD")
		)
		(pad "5" smd rect
			(at 1.225042 -0.94996 270)
			(size 0.5588 1.3462)
			(layers "F.Cu" "F.Mask" "F.Paste")
			(net "P3V3_AUX")
		)
	)
)
